(kicad_pcb
	(version 20260206)
	(generator "pcbnew")
	(generator_version "10.0")
	(general
		(thickness 1.6)
		(legacy_teardrops no)
	)
	(paper "A4")
	(title_block
		(title "04192023_DAF0TMB3IC0_F0TG_MB_C_brd_V02_OCP.brd")
		(comment 1 "Grand Teton / footprints 6668-6675 of 8354")
	)
	(layers
		(0 "F.Cu" signal "TOP")
		(4 "In1.Cu" signal "GND")
		(6 "In2.Cu" signal "IN1")
		(8 "In3.Cu" signal "GND1")
		(10 "In4.Cu" signal "IN2")
		(12 "In5.Cu" signal "GND2")
		(14 "In6.Cu" signal "IN3")
		(16 "In7.Cu" signal "GND3")
		(18 "In8.Cu" signal "VCC")
		(20 "In9.Cu" signal "VCC1")
		(22 "In10.Cu" signal "GND4")
		(24 "In11.Cu" signal "IN4")
		(26 "In12.Cu" signal "GND5")
		(28 "In13.Cu" signal "IN5")
		(30 "In14.Cu" signal "GND6")
		(32 "In15.Cu" signal "IN6")
		(34 "In16.Cu" signal "GND7")
		(2 "B.Cu" signal "BOTTOM")
		(9 "F.Adhes" user "F.Adhesive")
		(11 "B.Adhes" user "B.Adhesive")
		(13 "F.Paste" user "Package Geometry/Pastemask Top")
		(15 "B.Paste" user "Package Geometry/Pastemask Bottom")
		(5 "F.SilkS" user "Ref Des/Silkscreen Top")
		(7 "B.SilkS" user "Ref Des/Silkscreen Bottom")
		(1 "F.Mask" user "Board Geometry/Soldermask Top")
		(3 "B.Mask" user "Board Geometry/Soldermask Bottom")
		(17 "Dwgs.User" user "User.Drawings")
		(19 "Cmts.User" user "User.Comments")
		(21 "Eco1.User" user "User.Eco1")
		(23 "Eco2.User" user "User.Eco2")
		(25 "Edge.Cuts" user "Board Geometry/Outline")
		(27 "Margin" user)
		(31 "F.CrtYd" user "Package Geometry/Place Bound Top")
		(29 "B.CrtYd" user "Package Geometry/Place Bound Bottom")
		(35 "F.Fab" user "Ref Des/Assembly Top")
		(33 "B.Fab" user "Ref Des/Assembly Bottom")
	)
	(footprint ""
		(layer "B.Cu")
		(at 352.120454 -268.41831)
		(property "Reference" "C2220"
			(at 0 0 0)
			(layer "B.SilkS")
			(hide yes)
			(effects
				(font
					(size 1.27 1.27)
				)
				(justify mirror)
			)
		)
		(property "Value" ""
			(at 0 0 0)
			(layer "B.Fab")
			(effects
				(font
					(size 1.27 1.27)
				)
				(justify mirror)
			)
		)
		(duplicate_pad_numbers_are_jumpers no)
		(fp_line
			(start -0.7874 -0.4064)
			(end -0.7874 0.4064)
			(stroke
				(width 0.1524)
				(type default)
			)
			(layer "B.SilkS")
		)
		(fp_line
			(start -0.7874 0.4064)
			(end 0.7874 0.4064)
			(stroke
				(width 0.1524)
				(type default)
			)
			(layer "B.SilkS")
		)
		(fp_line
			(start 0.7874 -0.4064)
			(end -0.7874 -0.4064)
			(stroke
				(width 0.1524)
				(type default)
			)
			(layer "B.SilkS")
		)
		(fp_line
			(start 0.7874 0.4064)
			(end 0.7874 -0.4064)
			(stroke
				(width 0.1524)
				(type default)
			)
			(layer "B.SilkS")
		)
		(fp_line
			(start -0.67945 -0.3048)
			(end -0.67945 0.3048)
			(stroke
				(width 0.1)
				(type default)
			)
			(layer "B.Fab")
		)
		(fp_line
			(start -0.67945 0.3048)
			(end -0.120396 0.3048)
			(stroke
				(width 0.1)
				(type default)
			)
			(layer "B.Fab")
		)
		(fp_line
			(start -0.12065 -0.3048)
			(end -0.67945 -0.3048)
			(stroke
				(width 0.1)
				(type default)
			)
			(layer "B.Fab")
		)
		(fp_line
			(start -0.12065 -0.2794)
			(end -0.12065 -0.3048)
			(stroke
				(width 0.1)
				(type default)
			)
			(layer "B.Fab")
		)
		(fp_line
			(start -0.120396 0.2794)
			(end 0.12065 0.2794)
			(stroke
				(width 0.1)
				(type default)
			)
			(layer "B.Fab")
		)
		(fp_line
			(start -0.120396 0.3048)
			(end -0.120396 0.2794)
			(stroke
				(width 0.1)
				(type default)
			)
			(layer "B.Fab")
		)
		(fp_line
			(start 0.12065 -0.305054)
			(end 0.12065 -0.2794)
			(stroke
				(width 0.1)
				(type default)
			)
			(layer "B.Fab")
		)
		(fp_line
			(start 0.12065 -0.2794)
			(end -0.12065 -0.2794)
			(stroke
				(width 0.1)
				(type default)
			)
			(layer "B.Fab")
		)
		(fp_line
			(start 0.12065 0.2794)
			(end 0.12065 0.3048)
			(stroke
				(width 0.1)
				(type default)
			)
			(layer "B.Fab")
		)
		(fp_line
			(start 0.12065 0.3048)
			(end 0.67945 0.3048)
			(stroke
				(width 0.1)
				(type default)
			)
			(layer "B.Fab")
		)
		(fp_line
			(start 0.67945 -0.305054)
			(end 0.12065 -0.305054)
			(stroke
				(width 0.1)
				(type default)
			)
			(layer "B.Fab")
		)
		(fp_line
			(start 0.67945 0.3048)
			(end 0.67945 -0.305054)
			(stroke
				(width 0.1)
				(type default)
			)
			(layer "B.Fab")
		)
		(pad "1" smd circle
			(at 0.40005 0 180)
			(size 0 0)
			(layers "B.Cu" "B.Mask" "B.Paste")
			(net "PVDDCR_CPU1_P0")
		)
		(pad "2" smd circle
			(at -0.40005 0 180)
			(size 0 0)
			(layers "B.Cu" "B.Mask" "B.Paste")
			(net "GND")
		)
	)
	(footprint ""
		(layer "B.Cu")
		(at 156.60624 -386.766562 90)
		(property "Reference" "C380"
			(at 0 0 90)
			(layer "B.SilkS")
			(hide yes)
			(effects
				(font
					(size 1.27 1.27)
				)
				(justify mirror)
			)
		)
		(property "Value" ""
			(at 0 0 90)
			(layer "B.Fab")
			(effects
				(font
					(size 1.27 1.27)
				)
				(justify mirror)
			)
		)
		(duplicate_pad_numbers_are_jumpers no)
		(fp_line
			(start 0.299974 -0.150114)
			(end -0.299974 -0.150114)
			(stroke
				(width 0.1)
				(type default)
			)
			(layer "B.Fab")
		)
		(fp_line
			(start -0.299974 -0.150114)
			(end -0.299974 0.150114)
			(stroke
				(width 0.1)
				(type default)
			)
			(layer "B.Fab")
		)
		(fp_line
			(start 0.299974 0.150114)
			(end 0.299974 -0.150114)
			(stroke
				(width 0.1)
				(type default)
			)
			(layer "B.Fab")
		)
		(fp_line
			(start -0.299974 0.150114)
			(end 0.299974 0.150114)
			(stroke
				(width 0.1)
				(type default)
			)
			(layer "B.Fab")
		)
		(pad "1" smd rect
			(at 0.2667 0 270)
			(size 0.3048 0.381)
			(layers "B.Cu" "B.Mask" "B.Paste")
			(net "P1V8_CPU1_RT2_1A")
		)
		(pad "2" smd rect
			(at -0.2667 0 270)
			(size 0.3048 0.381)
			(layers "B.Cu" "B.Mask" "B.Paste")
			(net "GND")
		)
	)
	(footprint ""
		(layer "B.Cu")
		(at 424.664124 -428.118524 90)
		(property "Reference" "R1432"
			(at 0 0 90)
			(layer "B.SilkS")
			(hide yes)
			(effects
				(font
					(size 1.27 1.27)
				)
				(justify mirror)
			)
		)
		(property "Value" ""
			(at 0 0 90)
			(layer "B.Fab")
			(effects
				(font
					(size 1.27 1.27)
				)
				(justify mirror)
			)
		)
		(duplicate_pad_numbers_are_jumpers no)
		(fp_line
			(start 0.32512 -0.175006)
			(end -0.32512 -0.175006)
			(stroke
				(width 0.1)
				(type default)
			)
			(layer "B.Fab")
		)
		(fp_line
			(start -0.32512 -0.175006)
			(end -0.32512 0.175006)
			(stroke
				(width 0.1)
				(type default)
			)
			(layer "B.Fab")
		)
		(fp_line
			(start 0.32512 0.175006)
			(end 0.32512 -0.175006)
			(stroke
				(width 0.1)
				(type default)
			)
			(layer "B.Fab")
		)
		(fp_line
			(start -0.32512 0.175006)
			(end 0.32512 0.175006)
			(stroke
				(width 0.1)
				(type default)
			)
			(layer "B.Fab")
		)
		(pad "1" smd rect
			(at 0.2667 0 270)
			(size 0.3048 0.381)
			(layers "B.Cu" "B.Mask" "B.Paste")
			(net "P1V8_CPU0_RT_1D")
		)
		(pad "2" smd rect
			(at -0.2667 0 90)
			(size 0.3048 0.381)
			(layers "B.Cu" "B.Mask" "B.Paste")
			(net "SMB_RT_CPU0_P2_ROM_MUX_1D_SCL")
		)
	)
	(footprint ""
		(layer "B.Cu")
		(at 330.523342 -393.96416 180)
		(property "Reference" "R1030"
			(at 0 0 0)
			(layer "B.SilkS")
			(hide yes)
			(effects
				(font
					(size 1.27 1.27)
				)
				(justify mirror)
			)
		)
		(property "Value" ""
			(at 0 0 0)
			(layer "B.Fab")
			(effects
				(font
					(size 1.27 1.27)
				)
				(justify mirror)
			)
		)
		(duplicate_pad_numbers_are_jumpers no)
		(fp_line
			(start 0.32512 0.175006)
			(end 0.32512 -0.175006)
			(stroke
				(width 0.1)
				(type default)
			)
			(layer "B.Fab")
		)
		(fp_line
			(start 0.32512 -0.175006)
			(end -0.32512 -0.175006)
			(stroke
				(width 0.1)
				(type default)
			)
			(layer "B.Fab")
		)
		(fp_line
			(start -0.32512 0.175006)
			(end 0.32512 0.175006)
			(stroke
				(width 0.1)
				(type default)
			)
			(layer "B.Fab")
		)
		(fp_line
			(start -0.32512 -0.175006)
			(end -0.32512 0.175006)
			(stroke
				(width 0.1)
				(type default)
			)
			(layer "B.Fab")
		)
		(pad "1" smd rect
			(at 0.2667 0)
			(size 0.3048 0.381)
			(layers "B.Cu" "B.Mask" "B.Paste")
			(net "P1V8_CPU0_RT_1D")
		)
		(pad "2" smd rect
			(at -0.2667 0 180)
			(size 0.3048 0.381)
			(layers "B.Cu" "B.Mask" "B.Paste")
			(net "TEST0_RT_CPU0_P1")
		)
	)
	(footprint ""
		(layer "B.Cu")
		(at 28.46324 -195.926964 180)
		(property "Reference" "R1701"
			(at 0 0 0)
			(layer "B.SilkS")
			(hide yes)
			(effects
				(font
					(size 1.27 1.27)
				)
				(justify mirror)
			)
		)
		(property "Value" ""
			(at 0 0 0)
			(layer "B.Fab")
			(effects
				(font
					(size 1.27 1.27)
				)
				(justify mirror)
			)
		)
		(duplicate_pad_numbers_are_jumpers no)
		(fp_line
			(start 0.7874 0.4064)
			(end 0.7874 -0.4064)
			(stroke
				(width 0.1524)
				(type default)
			)
			(layer "B.SilkS")
		)
		(fp_line
			(start 0.7874 -0.4064)
			(end -0.7874 -0.4064)
			(stroke
				(width 0.1524)
				(type default)
			)
			(layer "B.SilkS")
		)
		(fp_line
			(start -0.7874 0.4064)
			(end 0.7874 0.4064)
			(stroke
				(width 0.1524)
				(type default)
			)
			(layer "B.SilkS")
		)
		(fp_line
			(start -0.7874 -0.4064)
			(end -0.7874 0.4064)
			(stroke
				(width 0.1524)
				(type default)
			)
			(layer "B.SilkS")
		)
		(fp_line
			(start 0.67945 0.3048)
			(end 0.67945 -0.305054)
			(stroke
				(width 0.1)
				(type default)
			)
			(layer "B.Fab")
		)
		(fp_line
			(start 0.67945 -0.305054)
			(end 0.12065 -0.305054)
			(stroke
				(width 0.1)
				(type default)
			)
			(layer "B.Fab")
		)
		(fp_line
			(start 0.12065 0.3048)
			(end 0.67945 0.3048)
			(stroke
				(width 0.1)
				(type default)
			)
			(layer "B.Fab")
		)
		(fp_line
			(start 0.12065 0.2794)
			(end 0.12065 0.3048)
			(stroke
				(width 0.1)
				(type default)
			)
			(layer "B.Fab")
		)
		(fp_line
			(start 0.12065 -0.2794)
			(end -0.12065 -0.2794)
			(stroke
				(width 0.1)
				(type default)
			)
			(layer "B.Fab")
		)
		(fp_line
			(start 0.12065 -0.305054)
			(end 0.12065 -0.2794)
			(stroke
				(width 0.1)
				(type default)
			)
			(layer "B.Fab")
		)
		(fp_line
			(start -0.120396 0.3048)
			(end -0.120396 0.2794)
			(stroke
				(width 0.1)
				(type default)
			)
			(layer "B.Fab")
		)
		(fp_line
			(start -0.120396 0.2794)
			(end 0.12065 0.2794)
			(stroke
				(width 0.1)
				(type default)
			)
			(layer "B.Fab")
		)
		(fp_line
			(start -0.12065 -0.2794)
			(end -0.12065 -0.3048)
			(stroke
				(width 0.1)
				(type default)
			)
			(layer "B.Fab")
		)
		(fp_line
			(start -0.12065 -0.3048)
			(end -0.67945 -0.3048)
			(stroke
				(width 0.1)
				(type default)
			)
			(layer "B.Fab")
		)
		(fp_line
			(start -0.67945 0.3048)
			(end -0.120396 0.3048)
			(stroke
				(width 0.1)
				(type default)
			)
			(layer "B.Fab")
		)
		(fp_line
			(start -0.67945 -0.3048)
			(end -0.67945 0.3048)
			(stroke
				(width 0.1)
				(type default)
			)
			(layer "B.Fab")
		)
		(pad "1" smd circle
			(at 0.40005 0)
			(size 0 0)
			(layers "B.Cu" "B.Mask" "B.Paste")
			(net "I3C_SPD_DDRAF_CPU1_SDA")
		)
		(pad "2" smd circle
			(at -0.40005 0)
			(size 0 0)
			(layers "B.Cu" "B.Mask" "B.Paste")
			(net "I3C_SPD_DDRE_CPU1_SDA")
		)
	)
	(footprint ""
		(layer "B.Cu")
		(at 56.341264 -408.517344 90)
		(property "Reference" "C6665"
			(at 0 0 90)
			(layer "B.SilkS")
			(hide yes)
			(effects
				(font
					(size 1.27 1.27)
				)
				(justify mirror)
			)
		)
		(property "Value" ""
			(at 0 0 90)
			(layer "B.Fab")
			(effects
				(font
					(size 1.27 1.27)
				)
				(justify mirror)
			)
		)
		(duplicate_pad_numbers_are_jumpers no)
		(fp_line
			(start 0.299974 -0.150114)
			(end -0.299974 -0.150114)
			(stroke
				(width 0.1)
				(type default)
			)
			(layer "B.Fab")
		)
		(fp_line
			(start -0.299974 -0.150114)
			(end -0.299974 0.150114)
			(stroke
				(width 0.1)
				(type default)
			)
			(layer "B.Fab")
		)
		(fp_line
			(start 0.299974 0.150114)
			(end 0.299974 -0.150114)
			(stroke
				(width 0.1)
				(type default)
			)
			(layer "B.Fab")
		)
		(fp_line
			(start -0.299974 0.150114)
			(end 0.299974 0.150114)
			(stroke
				(width 0.1)
				(type default)
			)
			(layer "B.Fab")
		)
		(pad "1" smd rect
			(at 0.2667 0 270)
			(size 0.3048 0.381)
			(layers "B.Cu" "B.Mask" "B.Paste")
			(net "P5E_CPU1_P1_TX_BUF_C_DP<2>")
		)
		(pad "2" smd rect
			(at -0.2667 0 270)
			(size 0.3048 0.381)
			(layers "B.Cu" "B.Mask" "B.Paste")
			(net "P5E_CPU1_P1_TX_BUF_DP<2>")
		)
	)
	(footprint ""
		(layer "B.Cu")
		(at 339.134958 -306.828952 180)
		(property "Reference" "R729"
			(at 0 0 0)
			(layer "B.SilkS")
			(hide yes)
			(effects
				(font
					(size 1.27 1.27)
				)
				(justify mirror)
			)
		)
		(property "Value" ""
			(at 0 0 0)
			(layer "B.Fab")
			(effects
				(font
					(size 1.27 1.27)
				)
				(justify mirror)
			)
		)
		(duplicate_pad_numbers_are_jumpers no)
		(fp_line
			(start 0.7874 0.4064)
			(end 0.7874 -0.4064)
			(stroke
				(width 0.1524)
				(type default)
			)
			(layer "B.SilkS")
		)
		(fp_line
			(start 0.7874 -0.4064)
			(end -0.7874 -0.4064)
			(stroke
				(width 0.1524)
				(type default)
			)
			(layer "B.SilkS")
		)
		(fp_line
			(start -0.7874 0.4064)
			(end 0.7874 0.4064)
			(stroke
				(width 0.1524)
				(type default)
			)
			(layer "B.SilkS")
		)
		(fp_line
			(start -0.7874 -0.4064)
			(end -0.7874 0.4064)
			(stroke
				(width 0.1524)
				(type default)
			)
			(layer "B.SilkS")
		)
		(fp_line
			(start 0.67945 0.3048)
			(end 0.67945 -0.305054)
			(stroke
				(width 0.1)
				(type default)
			)
			(layer "B.Fab")
		)
		(fp_line
			(start 0.67945 -0.305054)
			(end 0.12065 -0.305054)
			(stroke
				(width 0.1)
				(type default)
			)
			(layer "B.Fab")
		)
		(fp_line
			(start 0.12065 0.3048)
			(end 0.67945 0.3048)
			(stroke
				(width 0.1)
				(type default)
			)
			(layer "B.Fab")
		)
		(fp_line
			(start 0.12065 0.2794)
			(end 0.12065 0.3048)
			(stroke
				(width 0.1)
				(type default)
			)
			(layer "B.Fab")
		)
		(fp_line
			(start 0.12065 -0.2794)
			(end -0.12065 -0.2794)
			(stroke
				(width 0.1)
				(type default)
			)
			(layer "B.Fab")
		)
		(fp_line
			(start 0.12065 -0.305054)
			(end 0.12065 -0.2794)
			(stroke
				(width 0.1)
				(type default)
			)
			(layer "B.Fab")
		)
		(fp_line
			(start -0.120396 0.3048)
			(end -0.120396 0.2794)
			(stroke
				(width 0.1)
				(type default)
			)
			(layer "B.Fab")
		)
		(fp_line
			(start -0.120396 0.2794)
			(end 0.12065 0.2794)
			(stroke
				(width 0.1)
				(type default)
			)
			(layer "B.Fab")
		)
		(fp_line
			(start -0.12065 -0.2794)
			(end -0.12065 -0.3048)
			(stroke
				(width 0.1)
				(type default)
			)
			(layer "B.Fab")
		)
		(fp_line
			(start -0.12065 -0.3048)
			(end -0.67945 -0.3048)
			(stroke
				(width 0.1)
				(type default)
			)
			(layer "B.Fab")
		)
		(fp_line
			(start -0.67945 0.3048)
			(end -0.120396 0.3048)
			(stroke
				(width 0.1)
				(type default)
			)
			(layer "B.Fab")
		)
		(fp_line
			(start -0.67945 -0.3048)
			(end -0.67945 0.3048)
			(stroke
				(width 0.1)
				(type default)
			)
			(layer "B.Fab")
		)
		(pad "1" smd circle
			(at 0.40005 0)
			(size 0 0)
			(layers "B.Cu" "B.Mask" "B.Paste")
			(net "PVDD18_S5_P0")
		)
		(pad "2" smd circle
			(at -0.40005 0)
			(size 0 0)
			(layers "B.Cu" "B.Mask" "B.Paste")
			(net "UART_CPU0_SCM_UART1_TX")
		)
	)
	(footprint ""
		(layer "B.Cu")
		(at 233.37012 -422.849548 90)
		(property "Reference" "C64"
			(at 0 0 90)
			(layer "B.SilkS")
			(hide yes)
			(effects
				(font
					(size 1.27 1.27)
				)
				(justify mirror)
			)
		)
		(property "Value" ""
			(at 0 0 90)
			(layer "B.Fab")
			(effects
				(font
					(size 1.27 1.27)
				)
				(justify mirror)
			)
		)
		(duplicate_pad_numbers_are_jumpers no)
		(fp_line
			(start 0.7874 -0.4064)
			(end -0.7874 -0.4064)
			(stroke
				(width 0.1524)
				(type default)
			)
			(layer "B.SilkS")
		)
		(fp_line
			(start -0.7874 -0.4064)
			(end -0.7874 0.4064)
			(stroke
				(width 0.1524)
				(type default)
			)
			(layer "B.SilkS")
		)
		(fp_line
			(start 0.7874 0.4064)
			(end 0.7874 -0.4064)
			(stroke
				(width 0.1524)
				(type default)
			)
			(layer "B.SilkS")
		)
		(fp_line
			(start -0.7874 0.4064)
			(end 0.7874 0.4064)
			(stroke
				(width 0.1524)
				(type default)
			)
			(layer "B.SilkS")
		)
		(fp_line
			(start 0.67945 -0.305054)
			(end 0.12065 -0.305054)
			(stroke
				(width 0.1)
				(type default)
			)
			(layer "B.Fab")
		)
		(fp_line
			(start 0.12065 -0.305054)
			(end 0.12065 -0.2794)
			(stroke
				(width 0.1)
				(type default)
			)
			(layer "B.Fab")
		)
		(fp_line
			(start -0.12065 -0.3048)
			(end -0.67945 -0.3048)
			(stroke
				(width 0.1)
				(type default)
			)
			(layer "B.Fab")
		)
		(fp_line
			(start -0.67945 -0.3048)
			(end -0.67945 0.3048)
			(stroke
				(width 0.1)
				(type default)
			)
			(layer "B.Fab")
		)
		(fp_line
			(start 0.12065 -0.2794)
			(end -0.12065 -0.2794)
			(stroke
				(width 0.1)
				(type default)
			)
			(layer "B.Fab")
		)
		(fp_line
			(start -0.12065 -0.2794)
			(end -0.12065 -0.3048)
			(stroke
				(width 0.1)
				(type default)
			)
			(layer "B.Fab")
		)
		(fp_line
			(start 0.12065 0.2794)
			(end 0.12065 0.3048)
			(stroke
				(width 0.1)
				(type default)
			)
			(layer "B.Fab")
		)
		(fp_line
			(start -0.120396 0.2794)
			(end 0.12065 0.2794)
			(stroke
				(width 0.1)
				(type default)
			)
			(layer "B.Fab")
		)
		(fp_line
			(start 0.67945 0.3048)
			(end 0.67945 -0.305054)
			(stroke
				(width 0.1)
				(type default)
			)
			(layer "B.Fab")
		)
		(fp_line
			(start 0.12065 0.3048)
			(end 0.67945 0.3048)
			(stroke
				(width 0.1)
				(type default)
			)
			(layer "B.Fab")
		)
		(fp_line
			(start -0.120396 0.3048)
			(end -0.120396 0.2794)
			(stroke
				(width 0.1)
				(type default)
			)
			(layer "B.Fab")
		)
		(fp_line
			(start -0.67945 0.3048)
			(end -0.120396 0.3048)
			(stroke
				(width 0.1)
				(type default)
			)
			(layer "B.Fab")
		)
		(pad "1" smd circle
			(at 0.40005 0 270)
			(size 0 0)
			(layers "B.Cu" "B.Mask" "B.Paste")
			(net "PDB_PRSNT_N")
		)
		(pad "2" smd circle
			(at -0.40005 0 270)
			(size 0 0)
			(layers "B.Cu" "B.Mask" "B.Paste")
			(net "GND")
		)
	)
)
